(kicad_pcb
	(version 20260206)
	(generator "pcbnew")
	(generator_version "10.0")
	(general
		(thickness 1.6)
		(legacy_teardrops no)
	)
	(paper "A4")
	(title_block
		(title "01162023_DA0F0TEBIF0_F0T_Expander_BD_F_brd_V02_OCP.brd")
		(comment 1 "Grand Teton / footprints 5383-5389 of 9728")
	)
	(layers
		(0 "F.Cu" signal "TOP")
		(4 "In1.Cu" signal "GND")
		(6 "In2.Cu" signal "VCC")
		(8 "In3.Cu" signal "VCC1")
		(10 "In4.Cu" signal "GND1")
		(12 "In5.Cu" signal "IN1")
		(14 "In6.Cu" signal "GND2")
		(16 "In7.Cu" signal "IN2")
		(18 "In8.Cu" signal "GND3")
		(20 "In9.Cu" signal "IN3")
		(22 "In10.Cu" signal "GND4")
		(24 "In11.Cu" signal "IN4")
		(26 "In12.Cu" signal "GND5")
		(28 "In13.Cu" signal "IN5")
		(30 "In14.Cu" signal "GND6")
		(32 "In15.Cu" signal "IN6")
		(34 "In16.Cu" signal "GND7")
		(2 "B.Cu" signal "BOTTOM")
		(9 "F.Adhes" user "F.Adhesive")
		(11 "B.Adhes" user "B.Adhesive")
		(13 "F.Paste" user "Package Geometry/Pastemask Top")
		(15 "B.Paste" user "Package Geometry/Pastemask Bottom")
		(5 "F.SilkS" user "Ref Des/Silkscreen Top")
		(7 "B.SilkS" user "Ref Des/Silkscreen Bottom")
		(1 "F.Mask" user "Board Geometry/Soldermask Top")
		(3 "B.Mask" user "Board Geometry/Soldermask Bottom")
		(17 "Dwgs.User" user "User.Drawings")
		(19 "Cmts.User" user "User.Comments")
		(21 "Eco1.User" user "User.Eco1")
		(23 "Eco2.User" user "User.Eco2")
		(25 "Edge.Cuts" user "Board Geometry/Outline")
		(27 "Margin" user)
		(31 "F.CrtYd" user "Package Geometry/Place Bound Top")
		(29 "B.CrtYd" user "Package Geometry/Place Bound Bottom")
		(35 "F.Fab" user "Ref Des/Assembly Top")
		(33 "B.Fab" user "Ref Des/Assembly Bottom")
	)
	(footprint ""
		(layer "F.Cu")
		(at 136.77519 -56.977534 180)
		(property "Reference" "PC316"
			(at 0 0 180)
			(layer "F.SilkS")
			(hide yes)
			(effects
				(font
					(size 1.27 1.27)
				)
			)
		)
		(property "Value" ""
			(at 0 0 180)
			(layer "F.Fab")
			(effects
				(font
					(size 1.27 1.27)
				)
			)
		)
		(duplicate_pad_numbers_are_jumpers no)
		(fp_line
			(start 0.7874 0.4064)
			(end -0.7874 0.4064)
			(stroke
				(width 0.1524)
				(type default)
			)
			(layer "F.SilkS")
		)
		(fp_line
			(start 0.7874 -0.4064)
			(end 0.7874 0.4064)
			(stroke
				(width 0.1524)
				(type default)
			)
			(layer "F.SilkS")
		)
		(fp_line
			(start -0.7874 0.4064)
			(end -0.7874 -0.4064)
			(stroke
				(width 0.1524)
				(type default)
			)
			(layer "F.SilkS")
		)
		(fp_line
			(start -0.7874 -0.4064)
			(end 0.7874 -0.4064)
			(stroke
				(width 0.1524)
				(type default)
			)
			(layer "F.SilkS")
		)
		(fp_line
			(start 0.67945 0.3048)
			(end 0.120396 0.3048)
			(stroke
				(width 0.1)
				(type default)
			)
			(layer "F.Fab")
		)
		(fp_line
			(start 0.67945 -0.3048)
			(end 0.67945 0.3048)
			(stroke
				(width 0.1)
				(type default)
			)
			(layer "F.Fab")
		)
		(fp_line
			(start 0.12065 -0.2794)
			(end 0.12065 -0.3048)
			(stroke
				(width 0.1)
				(type default)
			)
			(layer "F.Fab")
		)
		(fp_line
			(start 0.12065 -0.3048)
			(end 0.67945 -0.3048)
			(stroke
				(width 0.1)
				(type default)
			)
			(layer "F.Fab")
		)
		(fp_line
			(start 0.120396 0.3048)
			(end 0.120396 0.2794)
			(stroke
				(width 0.1)
				(type default)
			)
			(layer "F.Fab")
		)
		(fp_line
			(start 0.120396 0.2794)
			(end -0.12065 0.2794)
			(stroke
				(width 0.1)
				(type default)
			)
			(layer "F.Fab")
		)
		(fp_line
			(start -0.12065 0.3048)
			(end -0.67945 0.3048)
			(stroke
				(width 0.1)
				(type default)
			)
			(layer "F.Fab")
		)
		(fp_line
			(start -0.12065 0.2794)
			(end -0.12065 0.3048)
			(stroke
				(width 0.1)
				(type default)
			)
			(layer "F.Fab")
		)
		(fp_line
			(start -0.12065 -0.2794)
			(end 0.12065 -0.2794)
			(stroke
				(width 0.1)
				(type default)
			)
			(layer "F.Fab")
		)
		(fp_line
			(start -0.12065 -0.305054)
			(end -0.12065 -0.2794)
			(stroke
				(width 0.1)
				(type default)
			)
			(layer "F.Fab")
		)
		(fp_line
			(start -0.67945 0.3048)
			(end -0.67945 -0.305054)
			(stroke
				(width 0.1)
				(type default)
			)
			(layer "F.Fab")
		)
		(fp_line
			(start -0.67945 -0.305054)
			(end -0.12065 -0.305054)
			(stroke
				(width 0.1)
				(type default)
			)
			(layer "F.Fab")
		)
		(pad "1" smd circle
			(at -0.40005 0 180)
			(size 0 0)
			(layers "F.Cu" "F.Mask" "F.Paste")
			(net "P12V_AUX")
		)
		(pad "2" smd circle
			(at 0.40005 0 180)
			(size 0 0)
			(layers "F.Cu" "F.Mask" "F.Paste")
			(net "GND")
		)
	)
	(footprint ""
		(layer "F.Cu")
		(at 459.324202 -248.684796 90)
		(property "Reference" "R6586"
			(at 0 0 90)
			(layer "F.SilkS")
			(hide yes)
			(effects
				(font
					(size 1.27 1.27)
				)
			)
		)
		(property "Value" ""
			(at 0 0 90)
			(layer "F.Fab")
			(effects
				(font
					(size 1.27 1.27)
				)
			)
		)
		(duplicate_pad_numbers_are_jumpers no)
		(fp_line
			(start 0.7874 -0.4064)
			(end 0.7874 0.4064)
			(stroke
				(width 0.1524)
				(type default)
			)
			(layer "F.SilkS")
		)
		(fp_line
			(start -0.7874 -0.4064)
			(end 0.7874 -0.4064)
			(stroke
				(width 0.1524)
				(type default)
			)
			(layer "F.SilkS")
		)
		(fp_line
			(start 0.7874 0.4064)
			(end -0.7874 0.4064)
			(stroke
				(width 0.1524)
				(type default)
			)
			(layer "F.SilkS")
		)
		(fp_line
			(start -0.7874 0.4064)
			(end -0.7874 -0.4064)
			(stroke
				(width 0.1524)
				(type default)
			)
			(layer "F.SilkS")
		)
		(fp_line
			(start -0.12065 -0.305054)
			(end -0.12065 -0.2794)
			(stroke
				(width 0.1)
				(type default)
			)
			(layer "F.Fab")
		)
		(fp_line
			(start -0.67945 -0.305054)
			(end -0.12065 -0.305054)
			(stroke
				(width 0.1)
				(type default)
			)
			(layer "F.Fab")
		)
		(fp_line
			(start 0.67945 -0.3048)
			(end 0.67945 0.3048)
			(stroke
				(width 0.1)
				(type default)
			)
			(layer "F.Fab")
		)
		(fp_line
			(start 0.12065 -0.3048)
			(end 0.67945 -0.3048)
			(stroke
				(width 0.1)
				(type default)
			)
			(layer "F.Fab")
		)
		(fp_line
			(start 0.12065 -0.2794)
			(end 0.12065 -0.3048)
			(stroke
				(width 0.1)
				(type default)
			)
			(layer "F.Fab")
		)
		(fp_line
			(start -0.12065 -0.2794)
			(end 0.12065 -0.2794)
			(stroke
				(width 0.1)
				(type default)
			)
			(layer "F.Fab")
		)
		(fp_line
			(start 0.120396 0.2794)
			(end -0.12065 0.2794)
			(stroke
				(width 0.1)
				(type default)
			)
			(layer "F.Fab")
		)
		(fp_line
			(start -0.12065 0.2794)
			(end -0.12065 0.3048)
			(stroke
				(width 0.1)
				(type default)
			)
			(layer "F.Fab")
		)
		(fp_line
			(start 0.67945 0.3048)
			(end 0.120396 0.3048)
			(stroke
				(width 0.1)
				(type default)
			)
			(layer "F.Fab")
		)
		(fp_line
			(start 0.120396 0.3048)
			(end 0.120396 0.2794)
			(stroke
				(width 0.1)
				(type default)
			)
			(layer "F.Fab")
		)
		(fp_line
			(start -0.12065 0.3048)
			(end -0.67945 0.3048)
			(stroke
				(width 0.1)
				(type default)
			)
			(layer "F.Fab")
		)
		(fp_line
			(start -0.67945 0.3048)
			(end -0.67945 -0.305054)
			(stroke
				(width 0.1)
				(type default)
			)
			(layer "F.Fab")
		)
		(pad "1" smd circle
			(at -0.40005 0 90)
			(size 0 0)
			(layers "F.Cu" "F.Mask" "F.Paste")
			(net "P1V8_PLL_PEX3_ADJ")
		)
		(pad "2" smd circle
			(at 0.40005 0 90)
			(size 0 0)
			(layers "F.Cu" "F.Mask" "F.Paste")
			(net "GND")
		)
	)
	(footprint ""
		(layer "F.Cu")
		(at 397.956532 -17.419574 180)
		(property "Reference" "R1719"
			(at 0 0 180)
			(layer "F.SilkS")
			(hide yes)
			(effects
				(font
					(size 1.27 1.27)
				)
			)
		)
		(property "Value" ""
			(at 0 0 180)
			(layer "F.Fab")
			(effects
				(font
					(size 1.27 1.27)
				)
			)
		)
		(duplicate_pad_numbers_are_jumpers no)
		(fp_line
			(start 0.7874 0.4064)
			(end -0.7874 0.4064)
			(stroke
				(width 0.1524)
				(type default)
			)
			(layer "F.SilkS")
		)
		(fp_line
			(start 0.7874 -0.4064)
			(end 0.7874 0.4064)
			(stroke
				(width 0.1524)
				(type default)
			)
			(layer "F.SilkS")
		)
		(fp_line
			(start -0.7874 0.4064)
			(end -0.7874 -0.4064)
			(stroke
				(width 0.1524)
				(type default)
			)
			(layer "F.SilkS")
		)
		(fp_line
			(start -0.7874 -0.4064)
			(end 0.7874 -0.4064)
			(stroke
				(width 0.1524)
				(type default)
			)
			(layer "F.SilkS")
		)
		(fp_line
			(start 0.67945 0.3048)
			(end 0.120396 0.3048)
			(stroke
				(width 0.1)
				(type default)
			)
			(layer "F.Fab")
		)
		(fp_line
			(start 0.67945 -0.3048)
			(end 0.67945 0.3048)
			(stroke
				(width 0.1)
				(type default)
			)
			(layer "F.Fab")
		)
		(fp_line
			(start 0.12065 -0.2794)
			(end 0.12065 -0.3048)
			(stroke
				(width 0.1)
				(type default)
			)
			(layer "F.Fab")
		)
		(fp_line
			(start 0.12065 -0.3048)
			(end 0.67945 -0.3048)
			(stroke
				(width 0.1)
				(type default)
			)
			(layer "F.Fab")
		)
		(fp_line
			(start 0.120396 0.3048)
			(end 0.120396 0.2794)
			(stroke
				(width 0.1)
				(type default)
			)
			(layer "F.Fab")
		)
		(fp_line
			(start 0.120396 0.2794)
			(end -0.12065 0.2794)
			(stroke
				(width 0.1)
				(type default)
			)
			(layer "F.Fab")
		)
		(fp_line
			(start -0.12065 0.3048)
			(end -0.67945 0.3048)
			(stroke
				(width 0.1)
				(type default)
			)
			(layer "F.Fab")
		)
		(fp_line
			(start -0.12065 0.2794)
			(end -0.12065 0.3048)
			(stroke
				(width 0.1)
				(type default)
			)
			(layer "F.Fab")
		)
		(fp_line
			(start -0.12065 -0.2794)
			(end 0.12065 -0.2794)
			(stroke
				(width 0.1)
				(type default)
			)
			(layer "F.Fab")
		)
		(fp_line
			(start -0.12065 -0.305054)
			(end -0.12065 -0.2794)
			(stroke
				(width 0.1)
				(type default)
			)
			(layer "F.Fab")
		)
		(fp_line
			(start -0.67945 0.3048)
			(end -0.67945 -0.305054)
			(stroke
				(width 0.1)
				(type default)
			)
			(layer "F.Fab")
		)
		(fp_line
			(start -0.67945 -0.305054)
			(end -0.12065 -0.305054)
			(stroke
				(width 0.1)
				(type default)
			)
			(layer "F.Fab")
		)
		(pad "1" smd circle
			(at -0.40005 0 180)
			(size 0 0)
			(layers "F.Cu" "F.Mask" "F.Paste")
			(net "P3V3_SSD13")
		)
		(pad "2" smd circle
			(at 0.40005 0 180)
			(size 0 0)
			(layers "F.Cu" "F.Mask" "F.Paste")
			(net "SMB_ISO_SSD13_SCL")
		)
	)
	(footprint ""
		(layer "F.Cu")
		(at 156.698442 -252.356874 -90)
		(property "Reference" "R1290"
			(at 0 0 270)
			(layer "F.SilkS")
			(hide yes)
			(effects
				(font
					(size 1.27 1.27)
				)
			)
		)
		(property "Value" ""
			(at 0 0 270)
			(layer "F.Fab")
			(effects
				(font
					(size 1.27 1.27)
				)
			)
		)
		(duplicate_pad_numbers_are_jumpers no)
		(fp_line
			(start -0.7874 0.4064)
			(end -0.7874 -0.4064)
			(stroke
				(width 0.1524)
				(type default)
			)
			(layer "F.SilkS")
		)
		(fp_line
			(start 0.7874 0.4064)
			(end -0.7874 0.4064)
			(stroke
				(width 0.1524)
				(type default)
			)
			(layer "F.SilkS")
		)
		(fp_line
			(start -0.7874 -0.4064)
			(end 0.7874 -0.4064)
			(stroke
				(width 0.1524)
				(type default)
			)
			(layer "F.SilkS")
		)
		(fp_line
			(start 0.7874 -0.4064)
			(end 0.7874 0.4064)
			(stroke
				(width 0.1524)
				(type default)
			)
			(layer "F.SilkS")
		)
		(fp_line
			(start -0.67945 0.3048)
			(end -0.67945 -0.305054)
			(stroke
				(width 0.1)
				(type default)
			)
			(layer "F.Fab")
		)
		(fp_line
			(start -0.12065 0.3048)
			(end -0.67945 0.3048)
			(stroke
				(width 0.1)
				(type default)
			)
			(layer "F.Fab")
		)
		(fp_line
			(start 0.120396 0.3048)
			(end 0.120396 0.2794)
			(stroke
				(width 0.1)
				(type default)
			)
			(layer "F.Fab")
		)
		(fp_line
			(start 0.67945 0.3048)
			(end 0.120396 0.3048)
			(stroke
				(width 0.1)
				(type default)
			)
			(layer "F.Fab")
		)
		(fp_line
			(start -0.12065 0.2794)
			(end -0.12065 0.3048)
			(stroke
				(width 0.1)
				(type default)
			)
			(layer "F.Fab")
		)
		(fp_line
			(start 0.120396 0.2794)
			(end -0.12065 0.2794)
			(stroke
				(width 0.1)
				(type default)
			)
			(layer "F.Fab")
		)
		(fp_line
			(start -0.12065 -0.2794)
			(end 0.12065 -0.2794)
			(stroke
				(width 0.1)
				(type default)
			)
			(layer "F.Fab")
		)
		(fp_line
			(start 0.12065 -0.2794)
			(end 0.12065 -0.3048)
			(stroke
				(width 0.1)
				(type default)
			)
			(layer "F.Fab")
		)
		(fp_line
			(start 0.12065 -0.3048)
			(end 0.67945 -0.3048)
			(stroke
				(width 0.1)
				(type default)
			)
			(layer "F.Fab")
		)
		(fp_line
			(start 0.67945 -0.3048)
			(end 0.67945 0.3048)
			(stroke
				(width 0.1)
				(type default)
			)
			(layer "F.Fab")
		)
		(fp_line
			(start -0.67945 -0.305054)
			(end -0.12065 -0.305054)
			(stroke
				(width 0.1)
				(type default)
			)
			(layer "F.Fab")
		)
		(fp_line
			(start -0.12065 -0.305054)
			(end -0.12065 -0.2794)
			(stroke
				(width 0.1)
				(type default)
			)
			(layer "F.Fab")
		)
		(pad "1" smd circle
			(at -0.40005 0 270)
			(size 0 0)
			(layers "F.Cu" "F.Mask" "F.Paste")
			(net "GND")
		)
		(pad "2" smd circle
			(at 0.40005 0 270)
			(size 0 0)
			(layers "F.Cu" "F.Mask" "F.Paste")
			(net "PEX1_MODE_SEL1")
		)
	)
	(footprint ""
		(layer "F.Cu")
		(at 351.17532 -63.086234)
		(property "Reference" "R6018"
			(at 0 0 0)
			(layer "F.SilkS")
			(hide yes)
			(effects
				(font
					(size 1.27 1.27)
				)
			)
		)
		(property "Value" ""
			(at 0 0 0)
			(layer "F.Fab")
			(effects
				(font
					(size 1.27 1.27)
				)
			)
		)
		(duplicate_pad_numbers_are_jumpers no)
		(fp_line
			(start -0.7874 -0.4064)
			(end 0.7874 -0.4064)
			(stroke
				(width 0.1524)
				(type default)
			)
			(layer "F.SilkS")
		)
		(fp_line
			(start -0.7874 0.4064)
			(end -0.7874 -0.4064)
			(stroke
				(width 0.1524)
				(type default)
			)
			(layer "F.SilkS")
		)
		(fp_line
			(start 0.7874 -0.4064)
			(end 0.7874 0.4064)
			(stroke
				(width 0.1524)
				(type default)
			)
			(layer "F.SilkS")
		)
		(fp_line
			(start 0.7874 0.4064)
			(end -0.7874 0.4064)
			(stroke
				(width 0.1524)
				(type default)
			)
			(layer "F.SilkS")
		)
		(fp_line
			(start -0.67945 -0.305054)
			(end -0.12065 -0.305054)
			(stroke
				(width 0.1)
				(type default)
			)
			(layer "F.Fab")
		)
		(fp_line
			(start -0.67945 0.3048)
			(end -0.67945 -0.305054)
			(stroke
				(width 0.1)
				(type default)
			)
			(layer "F.Fab")
		)
		(fp_line
			(start -0.12065 -0.305054)
			(end -0.12065 -0.2794)
			(stroke
				(width 0.1)
				(type default)
			)
			(layer "F.Fab")
		)
		(fp_line
			(start -0.12065 -0.2794)
			(end 0.12065 -0.2794)
			(stroke
				(width 0.1)
				(type default)
			)
			(layer "F.Fab")
		)
		(fp_line
			(start -0.12065 0.2794)
			(end -0.12065 0.3048)
			(stroke
				(width 0.1)
				(type default)
			)
			(layer "F.Fab")
		)
		(fp_line
			(start -0.12065 0.3048)
			(end -0.67945 0.3048)
			(stroke
				(width 0.1)
				(type default)
			)
			(layer "F.Fab")
		)
		(fp_line
			(start 0.120396 0.2794)
			(end -0.12065 0.2794)
			(stroke
				(width 0.1)
				(type default)
			)
			(layer "F.Fab")
		)
		(fp_line
			(start 0.120396 0.3048)
			(end 0.120396 0.2794)
			(stroke
				(width 0.1)
				(type default)
			)
			(layer "F.Fab")
		)
		(fp_line
			(start 0.12065 -0.3048)
			(end 0.67945 -0.3048)
			(stroke
				(width 0.1)
				(type default)
			)
			(layer "F.Fab")
		)
		(fp_line
			(start 0.12065 -0.2794)
			(end 0.12065 -0.3048)
			(stroke
				(width 0.1)
				(type default)
			)
			(layer "F.Fab")
		)
		(fp_line
			(start 0.67945 -0.3048)
			(end 0.67945 0.3048)
			(stroke
				(width 0.1)
				(type default)
			)
			(layer "F.Fab")
		)
		(fp_line
			(start 0.67945 0.3048)
			(end 0.120396 0.3048)
			(stroke
				(width 0.1)
				(type default)
			)
			(layer "F.Fab")
		)
		(pad "1" smd circle
			(at -0.40005 0)
			(size 0 0)
			(layers "F.Cu" "F.Mask" "F.Paste")
			(net "P12V_SSD12_R")
		)
		(pad "2" smd circle
			(at 0.40005 0)
			(size 0 0)
			(layers "F.Cu" "F.Mask" "F.Paste")
			(net "P12V_SSD12_PG_G1")
		)
	)
	(footprint ""
		(layer "F.Cu")
		(at 213.590886 -231.150922 90)
		(property "Reference" "R1550"
			(at 0 0 90)
			(layer "F.SilkS")
			(hide yes)
			(effects
				(font
					(size 1.27 1.27)
				)
			)
		)
		(property "Value" ""
			(at 0 0 90)
			(layer "F.Fab")
			(effects
				(font
					(size 1.27 1.27)
				)
			)
		)
		(duplicate_pad_numbers_are_jumpers no)
		(fp_line
			(start 0.7874 -0.4064)
			(end 0.7874 0.4064)
			(stroke
				(width 0.1524)
				(type default)
			)
			(layer "F.SilkS")
		)
		(fp_line
			(start -0.7874 -0.4064)
			(end 0.7874 -0.4064)
			(stroke
				(width 0.1524)
				(type default)
			)
			(layer "F.SilkS")
		)
		(fp_line
			(start 0.7874 0.4064)
			(end -0.7874 0.4064)
			(stroke
				(width 0.1524)
				(type default)
			)
			(layer "F.SilkS")
		)
		(fp_line
			(start -0.7874 0.4064)
			(end -0.7874 -0.4064)
			(stroke
				(width 0.1524)
				(type default)
			)
			(layer "F.SilkS")
		)
		(fp_line
			(start -0.12065 -0.305054)
			(end -0.12065 -0.2794)
			(stroke
				(width 0.1)
				(type default)
			)
			(layer "F.Fab")
		)
		(fp_line
			(start -0.67945 -0.305054)
			(end -0.12065 -0.305054)
			(stroke
				(width 0.1)
				(type default)
			)
			(layer "F.Fab")
		)
		(fp_line
			(start 0.67945 -0.3048)
			(end 0.67945 0.3048)
			(stroke
				(width 0.1)
				(type default)
			)
			(layer "F.Fab")
		)
		(fp_line
			(start 0.12065 -0.3048)
			(end 0.67945 -0.3048)
			(stroke
				(width 0.1)
				(type default)
			)
			(layer "F.Fab")
		)
		(fp_line
			(start 0.12065 -0.2794)
			(end 0.12065 -0.3048)
			(stroke
				(width 0.1)
				(type default)
			)
			(layer "F.Fab")
		)
		(fp_line
			(start -0.12065 -0.2794)
			(end 0.12065 -0.2794)
			(stroke
				(width 0.1)
				(type default)
			)
			(layer "F.Fab")
		)
		(fp_line
			(start 0.120396 0.2794)
			(end -0.12065 0.2794)
			(stroke
				(width 0.1)
				(type default)
			)
			(layer "F.Fab")
		)
		(fp_line
			(start -0.12065 0.2794)
			(end -0.12065 0.3048)
			(stroke
				(width 0.1)
				(type default)
			)
			(layer "F.Fab")
		)
		(fp_line
			(start 0.67945 0.3048)
			(end 0.120396 0.3048)
			(stroke
				(width 0.1)
				(type default)
			)
			(layer "F.Fab")
		)
		(fp_line
			(start 0.120396 0.3048)
			(end 0.120396 0.2794)
			(stroke
				(width 0.1)
				(type default)
			)
			(layer "F.Fab")
		)
		(fp_line
			(start -0.12065 0.3048)
			(end -0.67945 0.3048)
			(stroke
				(width 0.1)
				(type default)
			)
			(layer "F.Fab")
		)
		(fp_line
			(start -0.67945 0.3048)
			(end -0.67945 -0.305054)
			(stroke
				(width 0.1)
				(type default)
			)
			(layer "F.Fab")
		)
		(pad "1" smd circle
			(at -0.40005 0 90)
			(size 0 0)
			(layers "F.Cu" "F.Mask" "F.Paste")
			(net "SMB_PEX_LS_R_SDA")
		)
		(pad "2" smd circle
			(at 0.40005 0 90)
			(size 0 0)
			(layers "F.Cu" "F.Mask" "F.Paste")
			(net "SMB_PEX3_SDA")
		)
	)
	(footprint ""
		(layer "F.Cu")
		(at 431.032412 -350.098614 90)
		(property "Reference" "C805"
			(at 0 0 90)
			(layer "F.SilkS")
			(hide yes)
			(effects
				(font
					(size 1.27 1.27)
				)
			)
		)
		(property "Value" ""
			(at 0 0 90)
			(layer "F.Fab")
			(effects
				(font
					(size 1.27 1.27)
				)
			)
		)
		(duplicate_pad_numbers_are_jumpers no)
		(fp_line
			(start 0.299974 -0.150114)
			(end 0.299974 0.150114)
			(stroke
				(width 0.1)
				(type default)
			)
			(layer "F.Fab")
		)
		(fp_line
			(start -0.299974 -0.150114)
			(end 0.299974 -0.150114)
			(stroke
				(width 0.1)
				(type default)
			)
			(layer "F.Fab")
		)
		(fp_line
			(start 0.299974 0.150114)
			(end -0.299974 0.150114)
			(stroke
				(width 0.1)
				(type default)
			)
			(layer "F.Fab")
		)
		(fp_line
			(start -0.299974 0.150114)
			(end -0.299974 -0.150114)
			(stroke
				(width 0.1)
				(type default)
			)
			(layer "F.Fab")
		)
		(pad "1" smd rect
			(at -0.2667 0 90)
			(size 0.3048 0.381)
			(layers "F.Cu" "F.Mask" "F.Paste")
			(net "P5E_PEX3_STN7_TX_DN<122>")
		)
		(pad "2" smd rect
			(at 0.2667 0 90)
			(size 0.3048 0.381)
			(layers "F.Cu" "F.Mask" "F.Paste")
			(net "P5E_PEX3_STN7_TX_C_DN<122>")
		)
	)
)
